FILE_TYPE = MULTI_PHYS_TABLE;

PART 'FUSE'
CLASS=DISCRETE

{========================================================================================}
:CLS_PN          | VALUE       = JEDEC_TYPE               | ALT_SYMBOLS                | DESCRIPTION                                                | CPN_STATUS ;
{========================================================================================}
 'CL1001188A'    | '10A'      = 'SMC_F_240X106'          | '(SMC_F_240X106)'          | 'FUSE, 10A, 125V, 0.0056OHMS, 26.46A2SEC'                  | ''        
 'CL1001189A'    | '8A'       = 'SMC_F_240X106'          | '(SMC_F_240X106)'          | 'FUSE, 8A, 125V, 0.0077OHMS, 20.23A2SEC'                   | ''        
 'CL1001480A'    | '1/16A'    = 'SMC_F_240X106'          | '(SMC_F_240X106)'          | 'FUSE, 1/16A, 5.5OHMS, 0.00019A2SEC'                       | ''        
 'CL1001558A'    | '12A'      = 'SMC_F_240X106'          | '(SMC_F_240X106)'          | 'FUSE, 12A, 65 V, 0.0049OHMS, 47.97A2SEC'                  | ''        
 'CL1001559A'    | '3A'       = 'SMC_F_240X106'          | '(SMC_F_240X106)'          | 'FUSE, 3A, 125 V, 0.0227OHMS, 1.65A2SEC'                   | ''        
 'CL1001560A'    | '5A'       = 'SMC_F_240X106'          | '(SMC_F_240X106)'          | 'FUSE, 5A, 125 V, 0.0125OHMS, 5.566A2SEC'                  | ''        
 'CL1001556A'    | '2A'       = 'SMC_F_240X106'          | '(SMC_F_240X106)'          | 'FUSE, 2A, 125V, 0.0367OHMS, 0.53A2SEC'                    | ''        
 'CL1001557A'    | '1.5A'     = 'SMC_F_240X106'          | '(SMC_F_240X106)'          | 'FUSE, 1.5 A, 125 V, 0.063OHMS, 0.853A2SEC'                | ''        
 'CL1001611A'    | '2A'       = 'SMC_F_240X106'          | '(SMC_F_240X106)'          | 'FUSE, 2A, 125V, 0.0625OHMS, 8.2A2SEC'                     | ''        
 'CL1001612A'    | '1.5A'     = 'SMC_F_240X106'          | '(SMC_F_240X106)'          | 'FUSE, 1.5 A, 125 V, 0.093OHMS, 3.65A2SEC'                 | ''        
 'CL1001613A'    | '3A'       = 'SMC_F_240X106'          | '(SMC_F_240X106)'          | 'FUSE, 3A, 125 V, 0.034OHMS, 20.16A2SEC'                   | ''        
 'CL1001614A'    | '5A'       = 'SMC_F_240X106'          | '(SMC_F_240X106)'          | 'FUSE, 5A, 125 V, 0.0136OHMS, 53.72A2SEC'                  | ''        
 'CL1001645A'    | '4A'       = 'SMC_F_240X106'          | '(SMC_F_240X106)'          | 'FUSE, 4A, 125 V, 0.0186OHMS, 34.40A2SEC'                  | ''        
 'G280-00016-01' | '4A'       = 'SMC_F_240X106'          | '(SMC_F_240X106)'          | 'FUSE, 4A, 125 V, 0.0186OHMS, 34.40A2SEC'                  | ''        
 'CL1001650A'    | '20A'      = 'SMC_F_397X123'          | '(SMC_F_397X123)'          | 'FUSE,20A,125V,0.00230OHMS,18A2SEC'                        | ''        
 'CL1001658A'    | '0.5A'     = 'SMC_F_240X106'          | '(SMC_F_240X106)'          | 'FUSE, 0.5A, 125V, 0.0795A2SEC'                            | ''        
 'CL1001661A'    | '0.375A'   = 'SMC_F_240X106'          | '(SMC_F_240X106)'          | 'FUSE, 0.375A, 125 V, 1.2OHMS, 0.101A2SEC'                 | ''        
 'CL1001662A'    | '0.5A'     = 'SMC_F_240X106'          | '(SMC_F_240X106)'          | 'FUSE, 0.5A, 125 V, 0.7OHMS, 0.24A2SEC'                    | ''        
 'CL5001026A'    | '1.25A'    = 'SMC_F_125X060'          | '(SMC_F_125X060)'          | 'FUSE, 1.25A, 63VDC, FASTBLOW, SMD'                        | ''        
 'CL1003707A'    | '0.062A'   = 'SMC_F_240X106'          | '(SMC_F_240X106)'          | 'FUSE, 62MA,125VAC, 5.5OHM, UL'                            | ''        
 'CL1003715A'    | '0.2A'     = 'SMC_F_240X106'          | '(SMC_F_240X106)'          | 'FUS, 0.2A, 125VAC, UL, 6.1X2.7X3.15MM'                    | ''        
 'CL1003718A'    | '1A'       = 'R2_F335X157_P200_H315'  | '(R2_F335X157_P200_H315)'  | 'FUS, 1A, 250V, 5.8 A2SEC, RADIAL LEAD'                    | ''        
 'CL1003808A'    | '1A'       = 'SMC_F_397X123'          | '(SMC_F_397X123)'          | 'FUS, 1A, 250V, 10.17 A2SEC, SMA'                          | ''        
 'G280-10001-01' | '250MA'    = 'R2_F335_P200'           | '(R2_F335_P200)'           | 'FUS, 250MA, 250V, LEAD TYPE'                              | ''        
 'G280-10033-01' | '12A'      = 'SMC_F_240X106_V1'       | '(SMC_F_240X106_V1)'       | 'FUS,12A,72V,NON-RESETABLE, SMT'                           | ''        
 'G280-10034-01' | '8A'       = 'SMC_F_240X106_V1_H116'  | '(SMC_F_240X106_V1_H116)'  | 'FUSE, 8A, 125V, 0.0077OHMS, 20.23A2SEC, SMT'              | ''        
 'G280-10035-01' | '2A'       = 'SMC_F_240X106_V1_H116'  | '(SMC_F_240X106_V1_H116)'  | 'FUSE, 2A, 125V, 0.0367OHMS, 0.530A2SEC, SMT'              | ''        
 'G280-10036-01' | '0.5A'     = 'SMC_F_240X106_V1'       | '(SMC_F_240X106_V1)'       | 'FUS, 0.5A, 125V, NON-RESETABLE, SMT'                      | ''        
 'G280-00003-01' | '10A'      = 'SMC_F_240X106_V1_H116'  | '(SMC_F_240X106_V1_H116)'  | 'FUS,10A,NON-RESETABLE,SMT2411'                            | ''        
 'G280-10037-01' | '0.5A'     = 'SMC_F_240X106_V1_H116'  | '(SMC_F_240X106_V1_H116)'  | 'FUSE, 0.5A, 125V, 0.42OHMS, 0.0795A2SEC, SMT'             | ''        
 'G280-10039-01' | '6.3A'     = 'SMC_F_240X106_V1_H116'  | '(SMC_F_240X106_V1_H116)'  | 'FUS, 6.3A, 125V, 0.0096OHMS, 9.17A2SEC, SMT'              | ''        
 'G280-10038-01' | '20A'      = 'SMC_F_397X123'          | '(SMC_F_397X123)'          | 'FUS, 20A, 125V, 0.0023OHMS, 18A2SEC, SMT'                 | ''        
 'G280-10042-01' | '2.5A'     = 'SMC_F_240X106_V1_H116'  | '(SMC_F_240X106_V1_H116)'  | 'FUS, 2.5A, 125V, 0.0286OHMS, 1.029A2SEC, SMT'             | ''        
 'G280-10043-01' | '0.2A'     = 'SMC_F_240X106_V1_H116'  | '(SMC_F_240X106_V1_H116)'  | 'FUS, 0.2A, 125V, 0.8372OHMS, 0.0089A2SEC, SMT'            | ''        
 'G280-10046-01' | '1.25A'    = 'SMC_F_397X123'          | '(SMC_F_397X123)'          | 'FUS, 1.25A, 600V, NON-RESETABLE, SMT'                     | ''        
 'G280-10040-01' | '30A'      = 'SMC_F_397X123'          | '(SMC_F_397X123)'          | 'FUS, 30A, 125V, 0.00132OHMS, 81A2SEC, SMT'                | ''        
 'G280-10049-01' | '1A'       = 'SMC_0603R_H024'         | '(SMC_0603R_H024)'         | 'FUSE,1A,63V,0.310OHM,0.0593A2SEC,0603'                    | ''        
 'G280-10055-01' | '5A'       = 'SMC_F_240X106_V1'       | '(SMC_F_240X106_V1)'       | 'FUSE,5A,125V,SMT'                                         | ''        
 'G280-10057-01' | '7A'       = 'SMC_F_125X060_V1'       | '(SMC_F_125X060_V1)'       | 'FUSE,7A,24V,1206'                                         | ''        
 'G280-10044-01' | '0.25A'    = 'SMC_0603R_H022'         | '(SMC_0603R_H022)'         | 'FUSE,0.25A,32V,0603'                                      | ''        
 'G280-10060-01' | '8A'       = 'SMC_F_240X106_V1_H116'  | '(SMC_F_240X106_V1_H116)'  | 'FUSE,8A,75V,0.0088OHMS,137.34A2SEC,SMT'                   | ''        
 'G280-10062-01' | '40A'      = 'SMC_F_492X175'          | '(SMC_F_492X175)'          | 'FUS,40A,72V,NON-RESETABLE,SMT'                            | ''        
 'G280-10066-01' | '1.5A'     = 'SMC_F_127X101_H048'     | '(SMC_F_127X101_H048)'     | 'FUS,1.50A,6V,RESET FUSE,1210,SMD'                         | ''        
 'G280-10012-01' | '2.5A'     = 'SMC_0603R_H022'         | '(SMC_0603R_H022)'         | 'FUSE,2.5A,32V,0603'                                       | ''        
 'G280-10052-01' | '12A'      = 'SMC_F_126X064_H023'     | '(SMC_F_126X064_H023)'     | 'FUS,12A,32V,HIGH CURRENT 1206 FAST-ACTING FUSE'           | ''        
 'G280-00001-01' | '1.1A'     = 'SMC_F_186X134_H028'     | '(SMC_F_186X134_H028)'     | 'FUS,1.1A,RESETTABLE,MINISMD'                              | ''        
 'G280-10005-01' | '5A'       = 'SMC_0603R_H012'         | '(SMC_0603R_H012)'         | 'FUSE,5A_32V,0603'                                         | ''        
 'G280-10064-01' | '0.5A'     = 'SMC_F_397X123'          | '(SMC_F_397X123)'          | 'FUS,0.5A,600V,0.56OHMS,NON-RESETABLE,SMT'                 | ''        
 'G280-00011-01' | '2.6A'     = 'SMC_F_186X134_H060'     | '(SMC_F_186X134_H060)'     | 'RES,2.6A,16V,RESETABLE,SMT'                               | ''        
 'G280-10065-01' | '0.15A'    = 'SMC_F_127X101_V1'       | '(SMC_F_127X101_V1)'       | 'FUSE,PTC RESTTABLE FUSE,30V,0.15A,SMT'                    | ''        
 'G280-10067-01' | '1.5A'     = 'SMC_F_126X063_V2'       | '(SMC_F_126X063_V2)'       | 'FUS,1.5A,6V,RESETTABLE,1206'                              | ''        
 'G280-10016-01' | '4A'       = 'SMC_F_126X063'          | '(SMC_F_126X063)'          | 'FUS,4A,125V,3216,SMT'                                     | ''        
 'G280-10024-01' | '1.5A'     = 'SMC_F_179X128_V1'       | '(SMC_F_179X128_V1)'       | 'FUS,1.5A,24V,RESETABLE,SMT1812'                           | ''        
 'G280-10068-01' | '0.2A'     = 'SMC_F_127X101_V1_H039'  | '(SMC_F_127X101_V1_H039)'  | 'FUSE,PTC RESTTABLE FUSE,30V,0.2A,SMT'                     | ''        
 'G280-10069-01' | '3.1A'     = 'SMC_F_295X201'          | '(SMC_F_295X201)'          | 'FUS,3.1A,18V,RESETABLE,SMT'                               | ''        
 'G280-10070-01' | '70A'      = 'SMC_F_441X394'          | '(SMC_F_441X394)'          | 'FUS,70A,75V,RESETABLE,SMD'                                | ''        
 'G280-10061-01' | '3A'       = 'SMC_F_186X134_H060'     | '(SMC_F_186X134_H060)'     | 'FUS,3A,6V,RESETABLE,SMT'                                  | ''        
 'G280-10071-01' | '5A'       = 'SMC_F_127X063'          | '(SMC_F_127X063)'          | 'FUS,5A,6V,RESETABLE,SMT'                                  | 'OBSOLETE'
 'G280-10028-01' | '20A'      = 'SMC_F_129X064_H023'     | '(SMC_F_129X064_H023)'     | 'FUS,20A,32V,SMT'                                          | ''        
 'G280-10010-01' | '2A'       = 'SMC_0402R_H016'         | '(SMC_0402R_H016)'         | 'FUSE,2A,24V,0402'                                         | ''        
 'G280-10075-01' | '20A_65V'  = 'SMC_F_240X106_V1_H116'  | '(SMC_F_240X106_V1_H116)'  | 'FUSE, 20A, 65V, 0.00244OHMS, 154A2SEC, SMT'               | ''        
 'G280-10076-01' | '15A_65V'  = 'SMC_F_240X106_V1_H116'  | '(SMC_F_240X106_V1_H116)'  | 'FUSE, 15A, 65V, 0.0037OHMS, 97.82A2SEC, SMT'              | ''        
 'G280-10077-01' | '100A_75V' = 'SMC_F_441X394'          | '(SMC_F_441X394)'          | 'FUS,100A,75V,NON-RESETABLE,SMT'                           | ''        
 'G280-10078-01' | '20KA_90V' = 'SMC_F_236X327'          | '(SMC_F_236X327)'          | 'FUS,GDT,20KA,90V,RESETABLE,SMT'                           | ''        
 'A280-00001-JN' | '3A_6V'    = 'SMC_F_126X065_H0315'    | '(SMC_F_126X065_H0315)'    | 'FUS,3A,6V,RESETABLE,SMT'                                  | ''        
 'A280-00002-JN' | '3A_6V'    = 'SMC_F_126X065_H0394'    | '(SMC_F_126X065_H0394)'    | 'FUS,3A,6V,RESETABLE,SMT'                                  | 'NFND'        
 'G280-10079-01' | '0.5A_32V' = 'SMC_F_039X020'          | '(SMC_F_039X020)'          | 'FUS,0.5A,32V,NON-RESETABLE,SMT'                           | ''        
 'G280-10080-01' | '5A_32V'   = 'SMC_F_039X020'          | '(SMC_F_039X020)'          | 'FUS,5A,32V,NON-RESETABLE,SMT'                             | ''        
 'G280-10081-01' | '5A_16V'   = 'SMC_F_290X202_H063'     | '(SMC_F_290X202_H063)'     | 'FUS,5.0A,16V,RESETABLE,SMT'                               | ''        
 'G280-10082-01' | '10A_24V'  = 'SMC_F_126X063_V2_H0335' | '(SMC_F_126X063_V2_H0335)' | 'FUS,10A,24V,POLYMER PTC RESETTABLE,SMT'                   | ''        
 'G280-10083-01' | '1.5A_63V' = 'SMC_F_125X060_V2'       | '(SMC_F_125X060_V2)'       | 'FUS,1.5A,63V,NON-RESETABLE,1206 SMT'                      | ''        
 'G280-10084-01' | '1.75A_63V'= 'SMC_F_125X060_V2'       | '(SMC_F_125X060_V2)'       | 'FUS,1.75A,63V,NON-RESETABLE,1206 SMT'                     | ''        
 'A280-00003-JN' | '1.75A_63V'= 'SMC_F_122X063'          | '(SMC_F_122X063)'          | 'FUS,1.75A,63VDC,NON-RESETABLE,1206 SMT'                   | ''        
 'A280-00016-IB' | '4A'       = 'SMC_F_240X106'          | '(SMC_F_240X106)'          | 'FUS,4A,125V,NON-RESETABLE,38.80A2SEC,6.1X2.72X2.72MM,SMT' | ''        
 'A280-00004-JN' | '2A_6V'    = 'SMC_F_126X065'          | '(SMC_F_126X065)'          | 'FUS,2A,6VDC,RESETABLE,1206 SMT'                           | ''        
 'G280-00016-02' | '4A_125V'  = 'SMC_F_240X107'          | '(SMC_F_240X107)'          | 'FUS,4A,125V,NON-RESETABLE,38.80A2SEC,6.1X2.72X2.72MM,SMT' | ''        
 'G280-10040-02' | '30A_125V' = 'SMC_F_398X122'          | '(SMC_F_398X122)'          | 'FUS,30A,125V,NON-RESETABLE FUSE,81A2S,SMT'                | ''        
 'G280-10085-01' | '72V'      = 'SMC_F_484X177'          | '(SMC_F_484X177)'          | 'FUS,BRICK FUSE,100A,72VDC,NON-RESETABLE,SMT'              | ''        
 'G280-10025-01' | '32V'      = 'SMC_F_126X064'          | '(SMC_F_126X064)'          | 'FUS,15A,32V,HIGH CURRENT 1206 FAST-ACTING FUSE.'          | ''        

END_PART

END.

